# T6G (Grand Teton) — schematic netlist excerpt (pin names and nets, part order shuffled) for the footprints in the layout excerpt that follows; sources: Cadence DE-HDL packaged netlist, KiCad conversion of 04192023_DAF0TMB3IC0_F0TG_MB_C_brd_V02_OCP.brd

R814  Q_RES  10K 5% EMPTY  pkg 0402LF  page 164 : A = PVDD18_S5_P0 ; B = UART_CPU0_UART0_TX
C642  Q_CAP  1000PF 50V 5% X7R  pkg 0402  page 224 : A = PVDD11_S3_P1_EN_R ; B = GND

(kicad_pcb
	(version 20260206)
	(generator "pcbnew")
	(generator_version "10.0")
	(general
		(thickness 1.6)
		(legacy_teardrops no)
	)
	(paper "A4")
	(title_block
		(title "04192023_DAF0TMB3IC0_F0TG_MB_C_brd_V02_OCP.brd")
		(comment 1 "Grand Teton / footprints 2423-2425 of 8354")
	)
	(layers
		(0 "F.Cu" signal "TOP")
		(4 "In1.Cu" signal "GND")
		(6 "In2.Cu" signal "IN1")
		(8 "In3.Cu" signal "GND1")
		(10 "In4.Cu" signal "IN2")
		(12 "In5.Cu" signal "GND2")
		(14 "In6.Cu" signal "IN3")
		(16 "In7.Cu" signal "GND3")
		(18 "In8.Cu" signal "VCC")
		(20 "In9.Cu" signal "VCC1")
		(22 "In10.Cu" signal "GND4")
		(24 "In11.Cu" signal "IN4")
		(26 "In12.Cu" signal "GND5")
		(28 "In13.Cu" signal "IN5")
		(30 "In14.Cu" signal "GND6")
		(32 "In15.Cu" signal "IN6")
		(34 "In16.Cu" signal "GND7")
		(2 "B.Cu" signal "BOTTOM")
		(9 "F.Adhes" user "F.Adhesive")
		(11 "B.Adhes" user "B.Adhesive")
		(13 "F.Paste" user "Package Geometry/Pastemask Top")
		(15 "B.Paste" user "Package Geometry/Pastemask Bottom")
		(5 "F.SilkS" user "Ref Des/Silkscreen Top")
		(7 "B.SilkS" user "Ref Des/Silkscreen Bottom")
		(1 "F.Mask" user "Board Geometry/Soldermask Top")
		(3 "B.Mask" user "Board Geometry/Soldermask Bottom")
		(17 "Dwgs.User" user "User.Drawings")
		(19 "Cmts.User" user "User.Comments")
		(21 "Eco1.User" user "User.Eco1")
		(23 "Eco2.User" user "User.Eco2")
		(25 "Edge.Cuts" user "Board Geometry/Outline")
		(27 "Margin" user)
		(31 "F.CrtYd" user "Package Geometry/Place Bound Top")
		(29 "B.CrtYd" user "Package Geometry/Place Bound Bottom")
		(35 "F.Fab" user "Ref Des/Assembly Top")
		(33 "B.Fab" user "Ref Des/Assembly Bottom")
	)
	(footprint ""
		(layer "F.Cu")
		(at 54.594506 19.444716 -90)
		(property "Reference" "J90_CON"
			(at 0 0 270)
			(layer "F.SilkS")
			(hide yes)
			(effects
				(font
					(size 1.27 1.27)
				)
			)
		)
		(property "Value" ""
			(at 0 0 270)
			(layer "F.Fab")
			(effects
				(font
					(size 1.27 1.27)
				)
			)
		)
		(duplicate_pad_numbers_are_jumpers no)
		(pad "1" smd circle
			(at 0 0 270)
			(size 0.762 0.762)
			(layers "F.Cu" "F.Mask" "F.Paste")
			(net "Net_2617")
		)
	)
	(footprint ""
		(layer "F.Cu")
		(at 157.692852 -350.256856 180)
		(property "Reference" "C642"
			(at 0 0 180)
			(layer "F.SilkS")
			(hide yes)
			(effects
				(font
					(size 1.27 1.27)
				)
			)
		)
		(property "Value" ""
			(at 0 0 180)
			(layer "F.Fab")
			(effects
				(font
					(size 1.27 1.27)
				)
			)
		)
		(duplicate_pad_numbers_are_jumpers no)
		(fp_line
			(start 0.7874 0.4064)
			(end -0.7874 0.4064)
			(stroke
				(width 0.1524)
				(type default)
			)
			(layer "F.SilkS")
		)
		(fp_line
			(start 0.7874 -0.4064)
			(end 0.7874 0.4064)
			(stroke
				(width 0.1524)
				(type default)
			)
			(layer "F.SilkS")
		)
		(fp_line
			(start -0.7874 0.4064)
			(end -0.7874 -0.4064)
			(stroke
				(width 0.1524)
				(type default)
			)
			(layer "F.SilkS")
		)
		(fp_line
			(start -0.7874 -0.4064)
			(end 0.7874 -0.4064)
			(stroke
				(width 0.1524)
				(type default)
			)
			(layer "F.SilkS")
		)
		(fp_line
			(start 0.67945 0.3048)
			(end 0.120396 0.3048)
			(stroke
				(width 0.1)
				(type default)
			)
			(layer "F.Fab")
		)
		(fp_line
			(start 0.67945 -0.3048)
			(end 0.67945 0.3048)
			(stroke
				(width 0.1)
				(type default)
			)
			(layer "F.Fab")
		)
		(fp_line
			(start 0.12065 -0.2794)
			(end 0.12065 -0.3048)
			(stroke
				(width 0.1)
				(type default)
			)
			(layer "F.Fab")
		)
		(fp_line
			(start 0.12065 -0.3048)
			(end 0.67945 -0.3048)
			(stroke
				(width 0.1)
				(type default)
			)
			(layer "F.Fab")
		)
		(fp_line
			(start 0.120396 0.3048)
			(end 0.120396 0.2794)
			(stroke
				(width 0.1)
				(type default)
			)
			(layer "F.Fab")
		)
		(fp_line
			(start 0.120396 0.2794)
			(end -0.12065 0.2794)
			(stroke
				(width 0.1)
				(type default)
			)
			(layer "F.Fab")
		)
		(fp_line
			(start -0.12065 0.3048)
			(end -0.67945 0.3048)
			(stroke
				(width 0.1)
				(type default)
			)
			(layer "F.Fab")
		)
		(fp_line
			(start -0.12065 0.2794)
			(end -0.12065 0.3048)
			(stroke
				(width 0.1)
				(type default)
			)
			(layer "F.Fab")
		)
		(fp_line
			(start -0.12065 -0.2794)
			(end 0.12065 -0.2794)
			(stroke
				(width 0.1)
				(type default)
			)
			(layer "F.Fab")
		)
		(fp_line
			(start -0.12065 -0.305054)
			(end -0.12065 -0.2794)
			(stroke
				(width 0.1)
				(type default)
			)
			(layer "F.Fab")
		)
		(fp_line
			(start -0.67945 0.3048)
			(end -0.67945 -0.305054)
			(stroke
				(width 0.1)
				(type default)
			)
			(layer "F.Fab")
		)
		(fp_line
			(start -0.67945 -0.305054)
			(end -0.12065 -0.305054)
			(stroke
				(width 0.1)
				(type default)
			)
			(layer "F.Fab")
		)
		(pad "1" smd circle
			(at -0.40005 0 180)
			(size 0 0)
			(layers "F.Cu" "F.Mask" "F.Paste")
			(net "PVDD11_S3_P1_EN_R")
		)
		(pad "2" smd circle
			(at 0.40005 0 180)
			(size 0 0)
			(layers "F.Cu" "F.Mask" "F.Paste")
			(net "GND")
		)
	)
	(footprint ""
		(layer "F.Cu")
		(at 366.971326 -43.235118 -90)
		(property "Reference" "R814"
			(at 0 0 270)
			(layer "F.SilkS")
			(hide yes)
			(effects
				(font
					(size 1.27 1.27)
				)
			)
		)
		(property "Value" ""
			(at 0 0 270)
			(layer "F.Fab")
			(effects
				(font
					(size 1.27 1.27)
				)
			)
		)
		(duplicate_pad_numbers_are_jumpers no)
		(fp_line
			(start -0.7874 0.4064)
			(end -0.7874 -0.4064)
			(stroke
				(width 0.1524)
				(type default)
			)
			(layer "F.SilkS")
		)
		(fp_line
			(start 0.7874 0.4064)
			(end -0.7874 0.4064)
			(stroke
				(width 0.1524)
				(type default)
			)
			(layer "F.SilkS")
		)
		(fp_line
			(start -0.7874 -0.4064)
			(end 0.7874 -0.4064)
			(stroke
				(width 0.1524)
				(type default)
			)
			(layer "F.SilkS")
		)
		(fp_line
			(start 0.7874 -0.4064)
			(end 0.7874 0.4064)
			(stroke
				(width 0.1524)
				(type default)
			)
			(layer "F.SilkS")
		)
		(fp_line
			(start -0.67945 0.3048)
			(end -0.67945 -0.305054)
			(stroke
				(width 0.1)
				(type default)
			)
			(layer "F.Fab")
		)
		(fp_line
			(start -0.12065 0.3048)
			(end -0.67945 0.3048)
			(stroke
				(width 0.1)
				(type default)
			)
			(layer "F.Fab")
		)
		(fp_line
			(start 0.120396 0.3048)
			(end 0.120396 0.2794)
			(stroke
				(width 0.1)
				(type default)
			)
			(layer "F.Fab")
		)
		(fp_line
			(start 0.67945 0.3048)
			(end 0.120396 0.3048)
			(stroke
				(width 0.1)
				(type default)
			)
			(layer "F.Fab")
		)
		(fp_line
			(start -0.12065 0.2794)
			(end -0.12065 0.3048)
			(stroke
				(width 0.1)
				(type default)
			)
			(layer "F.Fab")
		)
		(fp_line
			(start 0.120396 0.2794)
			(end -0.12065 0.2794)
			(stroke
				(width 0.1)
				(type default)
			)
			(layer "F.Fab")
		)
		(fp_line
			(start -0.12065 -0.2794)
			(end 0.12065 -0.2794)
			(stroke
				(width 0.1)
				(type default)
			)
			(layer "F.Fab")
		)
		(fp_line
			(start 0.12065 -0.2794)
			(end 0.12065 -0.3048)
			(stroke
				(width 0.1)
				(type default)
			)
			(layer "F.Fab")
		)
		(fp_line
			(start 0.12065 -0.3048)
			(end 0.67945 -0.3048)
			(stroke
				(width 0.1)
				(type default)
			)
			(layer "F.Fab")
		)
		(fp_line
			(start 0.67945 -0.3048)
			(end 0.67945 0.3048)
			(stroke
				(width 0.1)
				(type default)
			)
			(layer "F.Fab")
		)
		(fp_line
			(start -0.67945 -0.305054)
			(end -0.12065 -0.305054)
			(stroke
				(width 0.1)
				(type default)
			)
			(layer "F.Fab")
		)
		(fp_line
			(start -0.12065 -0.305054)
			(end -0.12065 -0.2794)
			(stroke
				(width 0.1)
				(type default)
			)
			(layer "F.Fab")
		)
		(pad "1" smd circle
			(at -0.40005 0 270)
			(size 0 0)
			(layers "F.Cu" "F.Mask" "F.Paste")
			(net "PVDD18_S5_P0")
		)
		(pad "2" smd circle
			(at 0.40005 0 270)
			(size 0 0)
			(layers "F.Cu" "F.Mask" "F.Paste")
			(net "UART_CPU0_UART0_TX")
		)
	)
)
